(kicad_pcb
	(version 20260206)
	(generator "pcbnew")
	(generator_version "10.0")
	(general
		(thickness 1.6)
		(legacy_teardrops no)
	)
	(paper "A4")
	(title_block
		(title "pdpb — Lightning_PDPB_BRD.brd")
		(comment 1 "Lightning (Wiwynn / Facebook NVMe JBOF) / footprints 1074-1074 of 1140")
	)
	(layers
		(0 "F.Cu" signal "TOP")
		(4 "In1.Cu" signal "L2GND")
		(6 "In2.Cu" signal "L3")
		(8 "In3.Cu" signal "L4VCC")
		(10 "In4.Cu" signal "L5VCC")
		(12 "In5.Cu" signal "L6")
		(14 "In6.Cu" signal "L7GND")
		(2 "B.Cu" signal "BOTTOM")
		(9 "F.Adhes" user "F.Adhesive")
		(11 "B.Adhes" user "B.Adhesive")
		(13 "F.Paste" user "Package Geometry/Pastemask Top")
		(15 "B.Paste" user "Package Geometry/Pastemask Bottom")
		(5 "F.SilkS" user "Ref Des/Silkscreen Top")
		(7 "B.SilkS" user "Ref Des/Silkscreen Bottom")
		(1 "F.Mask" user "Board Geometry/Soldermask Top")
		(3 "B.Mask" user "Board Geometry/Soldermask Bottom")
		(17 "Dwgs.User" user "User.Drawings")
		(19 "Cmts.User" user "User.Comments")
		(21 "Eco1.User" user "User.Eco1")
		(23 "Eco2.User" user "User.Eco2")
		(25 "Edge.Cuts" user "Board Geometry/Outline")
		(27 "Margin" user)
		(31 "F.CrtYd" user "Package Geometry/Place Bound Top")
		(29 "B.CrtYd" user "Package Geometry/Place Bound Bottom")
		(35 "F.Fab" user "Ref Des/Assembly Top")
		(33 "B.Fab" user "Ref Des/Assembly Bottom")
	)
	(footprint ""
		(layer "F.Cu")
		(at 226.149916 -376.670062 90)
		(property "Reference" "J1"
			(at 0 0 90)
			(layer "F.SilkS")
			(hide yes)
			(effects
				(font
					(size 1.27 1.27)
				)
			)
		)
		(property "Value" "PCISLT68-14-GP-U1"
			(at -22.225 12.7508 90)
			(unlocked yes)
			(layer "F.Fab")
			(hide yes)
			(effects
				(font
					(size 1.016 1.016)
					(thickness 0.1524)
				)
			)
		)
		(property "Device Type" "SD-78827-0001"
			(at -22.225 11.2268 90)
			(unlocked yes)
			(layer "F.Fab")
			(hide yes)
			(effects
				(font
					(size 1.016 1.016)
					(thickness 0.1524)
				)
			)
		)
		(duplicate_pad_numbers_are_jumpers no)
		(fp_line
			(start 20.4724 -3.4036)
			(end 20.4724 0.0254)
			(stroke
				(width 0.1524)
				(type default)
			)
			(layer "F.SilkS")
		)
		(fp_line
			(start -20.4724 -3.4036)
			(end 20.4724 -3.4036)
			(stroke
				(width 0.1524)
				(type default)
			)
			(layer "F.SilkS")
		)
		(fp_line
			(start 23.749 0.0254)
			(end 23.749 4.6736)
			(stroke
				(width 0.1524)
				(type default)
			)
			(layer "F.SilkS")
		)
		(fp_line
			(start 20.4724 0.0254)
			(end 23.749 0.0254)
			(stroke
				(width 0.1524)
				(type default)
			)
			(layer "F.SilkS")
		)
		(fp_line
			(start -20.4724 0.0254)
			(end -20.4724 -3.4036)
			(stroke
				(width 0.1524)
				(type default)
			)
			(layer "F.SilkS")
		)
		(fp_line
			(start -23.749 0.0254)
			(end -20.4724 0.0254)
			(stroke
				(width 0.1524)
				(type default)
			)
			(layer "F.SilkS")
		)
		(fp_line
			(start 23.117556 1.803908)
			(end 23.117556 2.896108)
			(stroke
				(width 0.3048)
				(type default)
			)
			(layer "F.SilkS")
		)
		(fp_line
			(start -20.882356 1.803908)
			(end -20.882356 2.896108)
			(stroke
				(width 0.3048)
				(type default)
			)
			(layer "F.SilkS")
		)
		(fp_line
			(start 20.882356 2.896108)
			(end 20.882356 1.803908)
			(stroke
				(width 0.3048)
				(type default)
			)
			(layer "F.SilkS")
		)
		(fp_line
			(start -23.117556 2.896108)
			(end -23.117556 1.803908)
			(stroke
				(width 0.3048)
				(type default)
			)
			(layer "F.SilkS")
		)
		(fp_line
			(start 23.749 4.6736)
			(end 20.4724 4.6736)
			(stroke
				(width 0.1524)
				(type default)
			)
			(layer "F.SilkS")
		)
		(fp_line
			(start 20.4724 4.6736)
			(end 20.4724 12.0142)
			(stroke
				(width 0.1524)
				(type default)
			)
			(layer "F.SilkS")
		)
		(fp_line
			(start -20.4724 4.6736)
			(end -23.749 4.6736)
			(stroke
				(width 0.1524)
				(type default)
			)
			(layer "F.SilkS")
		)
		(fp_line
			(start -23.749 4.6736)
			(end -23.749 0.0254)
			(stroke
				(width 0.1524)
				(type default)
			)
			(layer "F.SilkS")
		)
		(fp_line
			(start 17.8435 10.3124)
			(end -17.8435 10.3124)
			(stroke
				(width 0.1524)
				(type default)
			)
			(layer "F.SilkS")
		)
		(fp_line
			(start -17.8435 10.3124)
			(end -17.8435 12.0142)
			(stroke
				(width 0.1524)
				(type default)
			)
			(layer "F.SilkS")
		)
		(fp_line
			(start 20.4724 12.0142)
			(end 17.8435 12.0142)
			(stroke
				(width 0.1524)
				(type default)
			)
			(layer "F.SilkS")
		)
		(fp_line
			(start 17.8435 12.0142)
			(end 17.8435 10.3124)
			(stroke
				(width 0.1524)
				(type default)
			)
			(layer "F.SilkS")
		)
		(fp_line
			(start -17.8435 12.0142)
			(end -20.4724 12.0142)
			(stroke
				(width 0.1524)
				(type default)
			)
			(layer "F.SilkS")
		)
		(fp_line
			(start -20.4724 12.0142)
			(end -20.4724 4.6736)
			(stroke
				(width 0.1524)
				(type default)
			)
			(layer "F.SilkS")
		)
		(fp_arc
			(start 20.882356 1.803908)
			(mid 21.999956 0.686308)
			(end 23.117556 1.803908)
			(stroke
				(width 0.3048)
				(type default)
			)
			(layer "F.SilkS")
		)
		(fp_arc
			(start -23.117556 1.803908)
			(mid -21.999956 0.686308)
			(end -20.882356 1.803908)
			(stroke
				(width 0.3048)
				(type default)
			)
			(layer "F.SilkS")
		)
		(fp_arc
			(start 23.117556 2.896108)
			(mid 21.999956 4.013708)
			(end 20.882356 2.896108)
			(stroke
				(width 0.3048)
				(type default)
			)
			(layer "F.SilkS")
		)
		(fp_arc
			(start -20.882356 2.896108)
			(mid -21.999956 4.013708)
			(end -23.117556 2.896108)
			(stroke
				(width 0.3048)
				(type default)
			)
			(layer "F.SilkS")
		)
		(fp_poly
			(pts
				(xy -20.2184 11.7602) (xy -20.2184 4.4196) (xy -23.495 4.4196) (xy -23.495 0.2794) (xy -20.2184 0.2794)
				(xy -20.2184 -3.1496) (xy 20.2184 -3.1496) (xy 20.2184 0.2794) (xy 23.495 0.2794) (xy 23.495 4.4196)
				(xy 20.2184 4.4196) (xy 20.2184 11.7602) (xy 18.0975 11.7602) (xy 18.0975 10.0584) (xy -18.0975 10.0584)
				(xy -18.0975 11.7602)
			)
			(stroke
				(width 0)
				(type default)
			)
			(fill no)
			(layer "F.CrtYd")
		)
		(fp_poly
			(pts
				(xy -21.2471 16.256) (xy -21.2471 4.9276) (xy -24.003 4.9276) (xy -24.003 -0.2286) (xy -20.7264 -0.2286)
				(xy -20.7264 -3.6576) (xy 20.7264 -3.6576) (xy 20.7264 -0.2286) (xy 24.003 -0.2286) (xy 24.003 -0.00635)
				(xy 20.2184 -0.00635) (xy 20.2184 -3.1496) (xy -20.2184 -3.1496) (xy -20.2184 0.2794) (xy -23.495 0.2794)
				(xy -23.495 4.4196) (xy -20.2184 4.4196) (xy -20.2184 11.7602) (xy -18.0975 11.7602) (xy -18.0975 10.0584)
				(xy 18.0975 10.0584) (xy 18.0975 11.7602) (xy 20.2184 11.7602) (xy 20.2184 4.4196) (xy 23.495 4.4196)
				(xy 23.495 0.2794) (xy 20.2184 0.2794) (xy 20.2184 0.00635) (xy 24.003 0.00635) (xy 24.003 4.9276)
				(xy 21.2471 4.9276) (xy 21.2471 16.256)
			)
			(stroke
				(width 0)
				(type default)
			)
			(fill no)
			(layer "F.CrtYd")
		)
		(fp_poly
			(pts
				(xy -21.2471 16.256) (xy -21.2471 4.9276) (xy -24.003 4.9276) (xy -24.003 -0.2286) (xy -20.7264 -0.2286)
				(xy -20.7264 -3.6576) (xy 20.7264 -3.6576) (xy 20.7264 -0.2286) (xy 24.003 -0.2286) (xy 24.003 4.9276)
				(xy 21.2471 4.9276) (xy 21.2471 16.256)
			)
			(stroke
				(width 0)
				(type default)
			)
			(fill no)
			(layer "F.Fab")
		)
		(pad "" np_thru_hole circle
			(at -18.999962 0 90)
			(size 0.254 0.254)
			(drill 1.8542)
			(layers "*.Cu" "*.Mask")
			(clearance 1.1557)
			(thermal_gap 1.1557)
		)
		(pad "" np_thru_hole circle
			(at 18.999962 0 90)
			(size 0.254 0.254)
			(drill 1.8542)
			(layers "*.Cu" "*.Mask")
			(clearance 1.1557)
			(thermal_gap 1.1557)
		)
		(pad "E1" smd rect
			(at -7.079996 1.240028 90)
			(size 0.508 2.0066)
			(layers "F.Cu" "F.Mask" "F.Paste")
			(net "PE_CLK100M_DR1_2_P")
		)
		(pad "E2" smd rect
			(at -6.279896 1.240028 90)
			(size 0.508 2.0066)
			(layers "F.Cu" "F.Mask" "F.Paste")
			(net "PE_CLK100M_DR1_2_N")
		)
		(pad "E3" smd rect
			(at -5.48005 1.240028 90)
			(size 0.508 2.0066)
			(layers "F.Cu" "F.Mask" "F.Paste")
			(net "P3V3")
		)
		(pad "E4" smd rect
			(at -4.67995 1.240028 90)
			(size 0.508 2.0066)
			(layers "F.Cu" "F.Mask" "F.Paste")
			(net "SSD1_PERST_N")
		)
		(pad "E5" smd rect
			(at -3.880104 1.240028 90)
			(size 0.508 2.0066)
			(layers "F.Cu" "F.Mask" "F.Paste")
			(net "SSD1_PERST_N")
		)
		(pad "E6" smd rect
			(at -3.080004 1.240028 90)
			(size 0.508 2.0066)
			(layers "F.Cu" "F.Mask" "F.Paste")
			(net "Net_1305")
		)
		(pad "E7" smd rect
			(at -15.48003 -1.949958 90)
			(size 0.508 2.0066)
			(layers "F.Cu" "F.Mask" "F.Paste")
			(net "PE_CLK100M_DR1_1_P")
		)
		(pad "E8" smd rect
			(at -14.67993 -1.949958 90)
			(size 0.508 2.0066)
			(layers "F.Cu" "F.Mask" "F.Paste")
			(net "PE_CLK100M_DR1_1_N")
		)
		(pad "E9" smd rect
			(at -13.880084 -1.949958 90)
			(size 0.508 2.0066)
			(layers "F.Cu" "F.Mask" "F.Paste")
			(net "GND")
		)
		(pad "E10" smd rect
			(at -13.079984 -1.949958 90)
			(size 0.508 2.0066)
			(layers "F.Cu" "F.Mask" "F.Paste")
			(net "PE_TX1_DR1_N")
		)
		(pad "E11" smd rect
			(at -12.279884 -1.949958 90)
			(size 0.508 2.0066)
			(layers "F.Cu" "F.Mask" "F.Paste")
			(net "PE_TX1_DR1_P")
		)
		(pad "E12" smd rect
			(at -11.480038 -1.949958 90)
			(size 0.508 2.0066)
			(layers "F.Cu" "F.Mask" "F.Paste")
			(net "GND")
		)
		(pad "E13" smd rect
			(at -10.679938 -1.949958 90)
			(size 0.508 2.0066)
			(layers "F.Cu" "F.Mask" "F.Paste")
			(net "PE_RX1_DR1_N")
		)
		(pad "E14" smd rect
			(at -9.880092 -1.949958 90)
			(size 0.508 2.0066)
			(layers "F.Cu" "F.Mask" "F.Paste")
			(net "PE_RX1_DR1_P")
		)
		(pad "E15" smd rect
			(at -9.079992 -1.949958 90)
			(size 0.508 2.0066)
			(layers "F.Cu" "F.Mask" "F.Paste")
			(net "GND")
		)
		(pad "E16" smd rect
			(at -8.279892 -1.949958 90)
			(size 0.508 2.0066)
			(layers "F.Cu" "F.Mask" "F.Paste")
			(net "Net_1312")
		)
		(pad "E17" smd rect
			(at 9.320022 -1.949958 90)
			(size 0.508 2.0066)
			(layers "F.Cu" "F.Mask" "F.Paste")
			(net "PE_TX4_DR1_N")
		)
		(pad "E18" smd rect
			(at 10.120122 -1.949958 90)
			(size 0.508 2.0066)
			(layers "F.Cu" "F.Mask" "F.Paste")
			(net "PE_TX4_DR1_P")
		)
		(pad "E19" smd rect
			(at 10.919968 -1.949958 90)
			(size 0.508 2.0066)
			(layers "F.Cu" "F.Mask" "F.Paste")
			(net "GND")
		)
		(pad "E20" smd rect
			(at 11.720068 -1.949958 90)
			(size 0.508 2.0066)
			(layers "F.Cu" "F.Mask" "F.Paste")
			(net "PE_RX4_DR1_N")
		)
		(pad "E21" smd rect
			(at 12.519914 -1.949958 90)
			(size 0.508 2.0066)
			(layers "F.Cu" "F.Mask" "F.Paste")
			(net "PE_RX4_DR1_P")
		)
		(pad "E22" smd rect
			(at 13.320014 -1.949958 90)
			(size 0.508 2.0066)
			(layers "F.Cu" "F.Mask" "F.Paste")
			(net "GND")
		)
		(pad "E23" smd rect
			(at 14.120114 -1.949958 90)
			(size 0.508 2.0066)
			(layers "F.Cu" "F.Mask" "F.Paste")
			(net "SCL_DR1_R")
		)
		(pad "E24" smd rect
			(at 14.91996 -1.949958 90)
			(size 0.508 2.0066)
			(layers "F.Cu" "F.Mask" "F.Paste")
			(net "SDA_DR1_R")
		)
		(pad "E25" smd rect
			(at 15.72006 -1.949958 90)
			(size 0.508 2.0066)
			(layers "F.Cu" "F.Mask" "F.Paste")
			(net "DUALPORTEN#1")
		)
		(pad "P1" smd rect
			(at -1.905 0.824992 90)
			(size 0.6604 2.0574)
			(layers "F.Cu" "F.Mask" "F.Paste")
			(net "Net_1308")
		)
		(pad "P2" smd rect
			(at -0.635 0.824992 90)
			(size 0.6604 2.0574)
			(layers "F.Cu" "F.Mask" "F.Paste")
			(net "Net_1307")
		)
		(pad "P3" smd rect
			(at 0.635 0.824992 90)
			(size 0.6604 2.0574)
			(layers "F.Cu" "F.Mask" "F.Paste")
			(net "Net_1306")
		)
		(pad "P4" smd rect
			(at 1.905 0.824992 90)
			(size 0.6604 2.0574)
			(layers "F.Cu" "F.Mask" "F.Paste")
			(net "SSD1_CLK0_OE_N")
		)
		(pad "P5" smd rect
			(at 3.175 0.824992 90)
			(size 0.6604 2.0574)
			(layers "F.Cu" "F.Mask" "F.Paste")
			(net "GND")
		)
		(pad "P6" smd rect
			(at 4.445 0.824992 90)
			(size 0.6604 2.0574)
			(layers "F.Cu" "F.Mask" "F.Paste")
			(net "GND")
		)
		(pad "P7" smd rect
			(at 5.715 0.824992 90)
			(size 0.6604 2.0574)
			(layers "F.Cu" "F.Mask" "F.Paste")
			(net "Net_94")
		)
		(pad "P8" smd rect
			(at 6.985 0.824992 90)
			(size 0.6604 2.0574)
			(layers "F.Cu" "F.Mask" "F.Paste")
			(net "Net_66")
		)
		(pad "P9" smd rect
			(at 8.255 0.824992 90)
			(size 0.6604 2.0574)
			(layers "F.Cu" "F.Mask" "F.Paste")
			(net "Net_80")
		)
		(pad "P10" smd rect
			(at 9.525 0.824992 90)
			(size 0.6604 2.0574)
			(layers "F.Cu" "F.Mask" "F.Paste")
			(net "SSD_PRSNT_NET1")
		)
		(pad "P11" smd rect
			(at 10.795 0.824992 90)
			(size 0.6604 2.0574)
			(layers "F.Cu" "F.Mask" "F.Paste")
			(net "SSD_ACT_DR1")
		)
		(pad "P12" smd rect
			(at 12.065 0.824992 90)
			(size 0.6604 2.0574)
			(layers "F.Cu" "F.Mask" "F.Paste")
			(net "GND")
		)
		(pad "P13" smd rect
			(at 13.335 0.824992 90)
			(size 0.6604 2.0574)
			(layers "F.Cu" "F.Mask" "F.Paste")
			(net "12V_PRECH_SSD1")
		)
		(pad "P14" smd rect
			(at 14.605 0.824992 90)
			(size 0.6604 2.0574)
			(layers "F.Cu" "F.Mask" "F.Paste")
			(net "P12V_SSD1")
		)
		(pad "P15" smd rect
			(at 15.875 0.824992 90)
			(size 0.6604 2.0574)
			(layers "F.Cu" "F.Mask" "F.Paste")
			(net "P12V_SSD1")
		)
		(pad "PTH1" thru_hole oval
			(at -21.999956 2.350008 90)
			(size 1.524 2.6162)
			(drill oval 0.8128 1.905)
			(layers "*.Cu" "*.Mask")
			(remove_unused_layers no)
			(net "Net_1317")
			(clearance 0.1524)
			(thermal_gap 0.1524)
		)
		(pad "PTH2" thru_hole oval
			(at 21.999956 2.350008 90)
			(size 1.524 2.6162)
			(drill oval 0.8128 1.905)
			(layers "*.Cu" "*.Mask")
			(remove_unused_layers no)
			(net "Net_1301")
			(clearance 0.1524)
			(thermal_gap 0.1524)
		)
		(pad "S1" smd rect
			(at -15.875 0.824992 90)
			(size 0.6604 2.0574)
			(layers "F.Cu" "F.Mask" "F.Paste")
			(net "GND")
		)
		(pad "S2" smd rect
			(at -14.605 0.824992 90)
			(size 0.6604 2.0574)
			(layers "F.Cu" "F.Mask" "F.Paste")
			(net "Net_1316")
		)
		(pad "S3" smd rect
			(at -13.335 0.824992 90)
			(size 0.6604 2.0574)
			(layers "F.Cu" "F.Mask" "F.Paste")
			(net "Net_1315")
		)
		(pad "S4" smd rect
			(at -12.065 0.824992 90)
			(size 0.6604 2.0574)
			(layers "F.Cu" "F.Mask" "F.Paste")
			(net "GND")
		)
		(pad "S5" smd rect
			(at -10.795 0.824992 90)
			(size 0.6604 2.0574)
			(layers "F.Cu" "F.Mask" "F.Paste")
			(net "Net_1314")
		)
		(pad "S6" smd rect
			(at -9.525 0.824992 90)
			(size 0.6604 2.0574)
			(layers "F.Cu" "F.Mask" "F.Paste")
			(net "Net_1313")
		)
		(pad "S7" smd rect
			(at -8.255 0.824992 90)
			(size 0.6604 2.0574)
			(layers "F.Cu" "F.Mask" "F.Paste")
			(net "GND")
		)
		(pad "S8" smd rect
			(at -7.480046 -1.949958 90)
			(size 0.508 2.0066)
			(layers "F.Cu" "F.Mask" "F.Paste")
			(net "GND")
		)
		(pad "S9" smd rect
			(at -6.679946 -1.949958 90)
			(size 0.508 2.0066)
			(layers "F.Cu" "F.Mask" "F.Paste")
			(net "Net_1311")
		)
		(pad "S10" smd rect
			(at -5.8801 -1.949958 90)
			(size 0.508 2.0066)
			(layers "F.Cu" "F.Mask" "F.Paste")
			(net "Net_1310")
		)
		(pad "S11" smd rect
			(at -5.08 -1.949958 90)
			(size 0.508 2.0066)
			(layers "F.Cu" "F.Mask" "F.Paste")
			(net "GND")
		)
		(pad "S12" smd rect
			(at -4.2799 -1.949958 90)
			(size 0.508 2.0066)
			(layers "F.Cu" "F.Mask" "F.Paste")
			(net "Net_1309")
		)
		(pad "S13" smd rect
			(at -3.480054 -1.949958 90)
			(size 0.508 2.0066)
			(layers "F.Cu" "F.Mask" "F.Paste")
			(net "Net_1304")
		)
		(pad "S14" smd rect
			(at -2.679954 -1.949958 90)
			(size 0.508 2.0066)
			(layers "F.Cu" "F.Mask" "F.Paste")
			(net "GND")
		)
		(pad "S15" smd rect
			(at -1.880108 -1.949958 90)
			(size 0.508 2.0066)
			(layers "F.Cu" "F.Mask" "F.Paste")
			(net "Net_1303")
		)
		(pad "S16" smd rect
			(at -1.080008 -1.949958 90)
			(size 0.508 2.0066)
			(layers "F.Cu" "F.Mask" "F.Paste")
			(net "GND")
		)
		(pad "S17" smd rect
			(at -0.279908 -1.949958 90)
			(size 0.508 2.0066)
			(layers "F.Cu" "F.Mask" "F.Paste")
			(net "PE_TX2_DR1_N")
		)
		(pad "S18" smd rect
			(at 0.519938 -1.949958 90)
			(size 0.508 2.0066)
			(layers "F.Cu" "F.Mask" "F.Paste")
			(net "PE_TX2_DR1_P")
		)
		(pad "S19" smd rect
			(at 1.320038 -1.949958 90)
			(size 0.508 2.0066)
			(layers "F.Cu" "F.Mask" "F.Paste")
			(net "GND")
		)
		(pad "S20" smd rect
			(at 2.119884 -1.949958 90)
			(size 0.508 2.0066)
			(layers "F.Cu" "F.Mask" "F.Paste")
			(net "PE_RX2_DR1_N")
		)
		(pad "S21" smd rect
			(at 2.919984 -1.949958 90)
			(size 0.508 2.0066)
			(layers "F.Cu" "F.Mask" "F.Paste")
			(net "PE_RX2_DR1_P")
		)
		(pad "S22" smd rect
			(at 3.720084 -1.949958 90)
			(size 0.508 2.0066)
			(layers "F.Cu" "F.Mask" "F.Paste")
			(net "GND")
		)
		(pad "S23" smd rect
			(at 4.51993 -1.949958 90)
			(size 0.508 2.0066)
			(layers "F.Cu" "F.Mask" "F.Paste")
			(net "PE_TX3_DR1_N")
		)
		(pad "S24" smd rect
			(at 5.32003 -1.949958 90)
			(size 0.508 2.0066)
			(layers "F.Cu" "F.Mask" "F.Paste")
			(net "PE_TX3_DR1_P")
		)
		(pad "S25" smd rect
			(at 6.119876 -1.949958 90)
			(size 0.508 2.0066)
			(layers "F.Cu" "F.Mask" "F.Paste")
			(net "GND")
		)
		(pad "S26" smd rect
			(at 6.919976 -1.949958 90)
			(size 0.508 2.0066)
			(layers "F.Cu" "F.Mask" "F.Paste")
			(net "PE_RX3_DR1_N")
		)
		(pad "S27" smd rect
			(at 7.720076 -1.949958 90)
			(size 0.508 2.0066)
			(layers "F.Cu" "F.Mask" "F.Paste")
			(net "PE_RX3_DR1_P")
		)
		(pad "S28" smd rect
			(at 8.519922 -1.949958 90)
			(size 0.508 2.0066)
			(layers "F.Cu" "F.Mask" "F.Paste")
			(net "GND")
		)
		(zone
			(layers "F.Cu" "B.Cu" "In1.Cu" "In2.Cu" "In3.Cu" "In4.Cu" "In5.Cu" "In6.Cu")
			(hatch none 0.5)
			(connect_pads
				(clearance 0)
			)
			(min_thickness 0.25)
			(keepout
				(tracks not_allowed)
				(vias allowed)
				(pads allowed)
				(copperpour not_allowed)
				(footprints allowed)
			)
			(placement
				(enabled no)
				(sheetname "")
			)
			(fill
				(thermal_gap 0.5)
				(thermal_bridge_width 0.5)
				(island_removal_mode 0)
			)
			(polygon
				(pts
					(arc
						(start 227.381816 -395.670024)
						(mid 224.918016 -395.670024)
						(end 227.381816 -395.670024)
					)
				)
			)
		)
		(zone
			(layers "F.Cu" "B.Cu" "In1.Cu" "In2.Cu" "In3.Cu" "In4.Cu" "In5.Cu" "In6.Cu")
			(hatch none 0.5)
			(connect_pads
				(clearance 0)
			)
			(min_thickness 0.25)
			(keepout
				(tracks not_allowed)
				(vias allowed)
				(pads allowed)
				(copperpour not_allowed)
				(footprints allowed)
			)
			(placement
				(enabled no)
				(sheetname "")
			)
			(fill
				(thermal_gap 0.5)
				(thermal_bridge_width 0.5)
				(island_removal_mode 0)
			)
			(polygon
				(pts
					(arc
						(start 227.381816 -357.6701)
						(mid 224.918016 -357.6701)
						(end 227.381816 -357.6701)
					)
				)
			)
		)
	)
)
